(kicad_pcb
	(version 20241229)
	(generator "pcbnew")
	(generator_version "9.0")
	(general
		(thickness 1.711)
		(legacy_teardrops no)
	)
	(paper "A4")
	(title_block
		(title "Antmicro Baseboard for Jetson AGX Thor")
		(date "2026-02-18")
		(rev "1.1.0")
		(company "Antmicro Ltd")
		(comment 1 "www.antmicro.com")
		(comment 9 "footprints 762-766 of 1170")
	)
	(layers
		(0 "F.Cu" signal)
		(4 "In1.Cu" signal)
		(6 "In2.Cu" signal)
		(8 "In3.Cu" signal)
		(10 "In4.Cu" jumper)
		(12 "In5.Cu" signal)
		(14 "In6.Cu" signal)
		(16 "In7.Cu" signal)
		(18 "In8.Cu" signal)
		(2 "B.Cu" signal)
		(9 "F.Adhes" user "F.Adhesive")
		(11 "B.Adhes" user "B.Adhesive")
		(13 "F.Paste" user)
		(15 "B.Paste" user)
		(5 "F.SilkS" user "F.Silkscreen")
		(7 "B.SilkS" user "B.Silkscreen")
		(1 "F.Mask" user)
		(3 "B.Mask" user)
		(17 "Dwgs.User" user "User.Drawings")
		(19 "Cmts.User" user "User.Comments")
		(21 "Eco1.User" user "User.Eco1")
		(23 "Eco2.User" user "User.Eco2")
		(25 "Edge.Cuts" user)
		(27 "Margin" user)
		(31 "F.CrtYd" user "F.Courtyard")
		(29 "B.CrtYd" user "B.Courtyard")
		(35 "F.Fab" user)
		(33 "B.Fab" user)
	)
	(footprint "antmicro-footprints:R_0402_1005Metric"
		(layer "B.Cu")
		(at 223 107.4)
		(descr "Resistor SMD 0402")
		(tags "resistor SMD 0402")
		(property "Reference" "R338"
			(at -1.5 -1.4 0)
			(layer "B.SilkS")
			(effects
				(font
					(size 0.7 0.7)
					(thickness 0.15)
				)
				(justify right top mirror)
			)
		)
		(property "Value" "R_10k_0402"
			(at -1.011843 -1.772047 0)
			(layer "B.Fab")
			(effects
				(font
					(size 0.7 0.7)
					(thickness 0.15)
				)
				(justify right top mirror)
			)
		)
		(property "Datasheet" "https://www.bourns.com/docs/product-datasheets/cr.pdf"
			(at 0 0 0)
			(layer "B.Fab")
			(hide yes)
			(effects
				(font
					(size 1.27 1.27)
					(thickness 0.15)
				)
				(justify mirror)
			)
		)
		(property "Description" "SMD Chip Resistor, 10 kohm, ± 1%, 62.5 mW, 0402 [1005 Metric], Thick Film, General Purpose"
			(at 0 0 0)
			(layer "B.Fab")
			(hide yes)
			(effects
				(font
					(size 1.27 1.27)
					(thickness 0.15)
				)
				(justify mirror)
			)
		)
		(property "Manufacturer" "Bourns"
			(at 0 0 180)
			(unlocked yes)
			(layer "B.Fab")
			(hide yes)
			(effects
				(font
					(size 1 1)
					(thickness 0.15)
				)
				(justify mirror)
			)
		)
		(property "MPN" "CR0402-FX-1002GLF"
			(at 0 0 180)
			(unlocked yes)
			(layer "B.Fab")
			(hide yes)
			(effects
				(font
					(size 1 1)
					(thickness 0.15)
				)
				(justify mirror)
			)
		)
		(property "Val" "10k"
			(at 0 0 180)
			(unlocked yes)
			(layer "B.Fab")
			(hide yes)
			(effects
				(font
					(size 1 1)
					(thickness 0.15)
				)
				(justify mirror)
			)
		)
		(property "License" "Apache-2.0"
			(at 0 0 180)
			(unlocked yes)
			(layer "B.Fab")
			(hide yes)
			(effects
				(font
					(size 1 1)
					(thickness 0.15)
				)
				(justify mirror)
			)
		)
		(property "Author" "Antmicro"
			(at 0 0 180)
			(unlocked yes)
			(layer "B.Fab")
			(hide yes)
			(effects
				(font
					(size 1 1)
					(thickness 0.15)
				)
				(justify mirror)
			)
		)
		(property "Tolerance" "1%"
			(at 0 0 180)
			(unlocked yes)
			(layer "B.Fab")
			(hide yes)
			(effects
				(font
					(size 1 1)
					(thickness 0.15)
				)
				(justify mirror)
			)
		)
		(sheetname "/Recovery USB/")
		(sheetfile "recovery_usb.kicad_sch")
		(attr smd)
		(fp_rect
			(start -0.925 0.47)
			(end 0.925 -0.47)
			(stroke
				(width 0.05)
				(type default)
			)
			(fill no)
			(layer "B.CrtYd")
		)
		(fp_rect
			(start -0.5 0.25)
			(end 0.5 -0.25)
			(stroke
				(width 0.15)
				(type solid)
			)
			(fill no)
			(layer "B.Fab")
		)
		(fp_text user "${REFERENCE}"
			(at -0.95 -3.168 0)
			(layer "B.Fab")
			(effects
				(font
					(size 0.7 0.7)
					(thickness 0.15)
				)
				(justify right top mirror)
			)
		)
		(fp_text user "License: Apache-2.0"
			(at -0.95 -5.169 0)
			(layer "B.Fab")
			(effects
				(font
					(size 0.7 0.7)
					(thickness 0.15)
				)
				(justify right top mirror)
			)
		)
		(fp_text user "Author: Antmicro"
			(at -0.95 -4.169 0)
			(layer "B.Fab")
			(effects
				(font
					(size 0.7 0.7)
					(thickness 0.15)
				)
				(justify right top mirror)
			)
		)
		(pad "1" smd roundrect
			(at -0.48 0)
			(size 0.59 0.64)
			(layers "B.Cu" "B.Mask" "B.Paste")
			(roundrect_rratio 0.25)
			(net 2 "+3V3")
			(pintype "passive")
		)
		(pad "2" smd roundrect
			(at 0.48 0)
			(size 0.59 0.64)
			(layers "B.Cu" "B.Mask" "B.Paste")
			(roundrect_rratio 0.25)
			(net 1018 "/Recovery USB/USBC2_VBUS_DET")
			(pintype "passive")
		)
	)
	(footprint "antmicro-footprints:R_0402_1005Metric"
		(layer "B.Cu")
		(at 208.726 148)
		(descr "Resistor SMD 0402")
		(tags "resistor SMD 0402")
		(property "Reference" "R189"
			(at 0.9 -0.3 0)
			(layer "B.SilkS")
			(effects
				(font
					(size 0.7 0.7)
					(thickness 0.15)
				)
				(justify right top mirror)
			)
		)
		(property "Value" "R_1k_0402"
			(at -1.011843 -1.772047 0)
			(layer "B.Fab")
			(effects
				(font
					(size 0.7 0.7)
					(thickness 0.15)
				)
				(justify right top mirror)
			)
		)
		(property "Datasheet" "https://www.bourns.com/docs/product-datasheets/cr.pdf"
			(at 0 0 0)
			(layer "B.Fab")
			(hide yes)
			(effects
				(font
					(size 1.27 1.27)
					(thickness 0.15)
				)
				(justify mirror)
			)
		)
		(property "Description" "SMD Chip Resistor, 1 kohm, ± 1%, 63 mW, 0402 [1005 Metric], Thick Film, General Purpose"
			(at 0 0 0)
			(layer "B.Fab")
			(hide yes)
			(effects
				(font
					(size 1.27 1.27)
					(thickness 0.15)
				)
				(justify mirror)
			)
		)
		(property "MPN" "CR0402-FX-1001GLF"
			(at 0 0 180)
			(unlocked yes)
			(layer "B.Fab")
			(hide yes)
			(effects
				(font
					(size 1 1)
					(thickness 0.15)
				)
				(justify mirror)
			)
		)
		(property "Manufacturer" "Bourns"
			(at 0 0 180)
			(unlocked yes)
			(layer "B.Fab")
			(hide yes)
			(effects
				(font
					(size 1 1)
					(thickness 0.15)
				)
				(justify mirror)
			)
		)
		(property "License" "Apache-2.0"
			(at 0 0 180)
			(unlocked yes)
			(layer "B.Fab")
			(hide yes)
			(effects
				(font
					(size 1 1)
					(thickness 0.15)
				)
				(justify mirror)
			)
		)
		(property "Author" "Antmicro"
			(at 0 0 180)
			(unlocked yes)
			(layer "B.Fab")
			(hide yes)
			(effects
				(font
					(size 1 1)
					(thickness 0.15)
				)
				(justify mirror)
			)
		)
		(property "Val" "1k"
			(at 0 0 180)
			(unlocked yes)
			(layer "B.Fab")
			(hide yes)
			(effects
				(font
					(size 1 1)
					(thickness 0.15)
				)
				(justify mirror)
			)
		)
		(property "Tolerance" "1%"
			(at 0 0 180)
			(unlocked yes)
			(layer "B.Fab")
			(hide yes)
			(effects
				(font
					(size 1 1)
					(thickness 0.15)
				)
				(justify mirror)
			)
		)
		(sheetname "/SFP/")
		(sheetfile "sfp.kicad_sch")
		(attr smd)
		(fp_rect
			(start -0.925 0.47)
			(end 0.925 -0.47)
			(stroke
				(width 0.05)
				(type default)
			)
			(fill no)
			(layer "B.CrtYd")
		)
		(fp_rect
			(start -0.5 0.25)
			(end 0.5 -0.25)
			(stroke
				(width 0.15)
				(type solid)
			)
			(fill no)
			(layer "B.Fab")
		)
		(fp_text user "${REFERENCE}"
			(at -0.95 -3.168 0)
			(layer "B.Fab")
			(effects
				(font
					(size 0.7 0.7)
					(thickness 0.15)
				)
				(justify right top mirror)
			)
		)
		(fp_text user "Author: Antmicro"
			(at -0.95 -4.169 0)
			(layer "B.Fab")
			(effects
				(font
					(size 0.7 0.7)
					(thickness 0.15)
				)
				(justify right top mirror)
			)
		)
		(fp_text user "License: Apache-2.0"
			(at -0.95 -5.169 0)
			(layer "B.Fab")
			(effects
				(font
					(size 0.7 0.7)
					(thickness 0.15)
				)
				(justify right top mirror)
			)
		)
		(pad "1" smd roundrect
			(at -0.48 0)
			(size 0.59 0.64)
			(layers "B.Cu" "B.Mask" "B.Paste")
			(roundrect_rratio 0.25)
			(net 1371 "Net-(J12-TX_{FAULT})")
			(pintype "passive")
		)
		(pad "2" smd roundrect
			(at 0.48 0)
			(size 0.59 0.64)
			(layers "B.Cu" "B.Mask" "B.Paste")
			(roundrect_rratio 0.25)
			(net 2 "+3V3")
			(pintype "passive")
		)
	)
	(footprint "antmicro-footprints:TP_SMD_0.75mm"
		(layer "B.Cu")
		(at 142.65 70 -90)
		(property "Reference" "TP80"
			(at 0.3 -3.25 0)
			(layer "B.SilkS")
			(effects
				(font
					(size 0.7 0.7)
					(thickness 0.15)
				)
				(justify left bottom mirror)
			)
		)
		(property "Value" "TP_0.75mm_SMD"
			(at 0 -1.2 90)
			(layer "B.Fab")
			(effects
				(font
					(size 0.7 0.7)
					(thickness 0.15)
				)
				(justify left bottom mirror)
			)
		)
		(property "Description" "SMT test point"
			(at 0 0 90)
			(layer "B.Fab")
			(hide yes)
			(effects
				(font
					(size 1.27 1.27)
					(thickness 0.15)
				)
				(justify mirror)
			)
		)
		(property "MPN" ""
			(at 0 0 90)
			(unlocked yes)
			(layer "B.Fab")
			(hide yes)
			(effects
				(font
					(size 1 1)
					(thickness 0.15)
				)
				(justify mirror)
			)
		)
		(property "Manufacturer" ""
			(at 0 0 90)
			(unlocked yes)
			(layer "B.Fab")
			(hide yes)
			(effects
				(font
					(size 1 1)
					(thickness 0.15)
				)
				(justify mirror)
			)
		)
		(property "Author" "Antmicro"
			(at 0 0 90)
			(unlocked yes)
			(layer "B.Fab")
			(hide yes)
			(effects
				(font
					(size 1 1)
					(thickness 0.15)
				)
				(justify mirror)
			)
		)
		(property "License" "Apache-2.0"
			(at 0 0 90)
			(unlocked yes)
			(layer "B.Fab")
			(hide yes)
			(effects
				(font
					(size 1 1)
					(thickness 0.15)
				)
				(justify mirror)
			)
		)
		(sheetname "/SoM_Power/")
		(sheetfile "som_power.kicad_sch")
		(attr exclude_from_pos_files exclude_from_bom)
		(fp_circle
			(center 0 0)
			(end 0.475 0)
			(stroke
				(width 0.05)
				(type default)
			)
			(fill no)
			(layer "B.CrtYd")
		)
		(fp_text user "Author: Antmicro"
			(at -0.4 -3.901 90)
			(layer "B.Fab")
			(effects
				(font
					(size 0.7 0.7)
					(thickness 0.15)
				)
				(justify left bottom mirror)
			)
		)
		(fp_text user "License: Apache-2.0"
			(at -0.4 -5.101 90)
			(layer "B.Fab")
			(effects
				(font
					(size 0.7 0.7)
					(thickness 0.15)
				)
				(justify left bottom mirror)
			)
		)
		(fp_text user "${REFERENCE}"
			(at -0.4 -2.7 90)
			(layer "B.Fab")
			(effects
				(font
					(size 0.7 0.7)
					(thickness 0.15)
				)
				(justify left bottom mirror)
			)
		)
		(pad "1" smd circle
			(at 0 0 270)
			(size 0.75 0.75)
			(layers "B.Cu" "B.Mask")
			(net 85 "/SoM_Power/~{SOM_POWER_BTN}")
			(pinfunction "1")
			(pintype "passive")
		)
	)
	(footprint "antmicro-footprints:Mech_Lightpipe_Bivar_SLP3-150-150-F"
		(locked yes)
		(layer "B.Cu")
		(at 232.829 59.489999 -90)
		(property "Reference" "H15"
			(at 0 1.6 90)
			(unlocked yes)
			(layer "B.SilkS")
			(effects
				(font
					(size 0.7 0.7)
					(thickness 0.15)
				)
				(justify left bottom mirror)
			)
		)
		(property "Value" "Lightpipe_Bivar_SLP3-150-150-F"
			(at 0 -6.6 90)
			(unlocked yes)
			(layer "B.Fab")
			(effects
				(font
					(size 0.7 0.7)
					(thickness 0.15)
				)
				(justify left bottom mirror)
			)
		)
		(property "Datasheet" "https://eu.mouser.com/datasheet/2/50/Bivar_SLP3_150_XXX_X_N-3318840.pdf"
			(at 0 0 90)
			(layer "B.Fab")
			(hide yes)
			(effects
				(font
					(size 1.27 1.27)
					(thickness 0.15)
				)
				(justify mirror)
			)
		)
		(property "Description" "LED Light Pipe, Rigid Board, Horizontal"
			(at 0 0 90)
			(layer "B.Fab")
			(hide yes)
			(effects
				(font
					(size 1.27 1.27)
					(thickness 0.15)
				)
				(justify mirror)
			)
		)
		(property "Manufacturer" "BIVAR"
			(at 0 0 90)
			(unlocked yes)
			(layer "B.Fab")
			(hide yes)
			(effects
				(font
					(size 1 1)
					(thickness 0.15)
				)
				(justify mirror)
			)
		)
		(property "MPN" "SLP3-150-150-F"
			(at 0 0 90)
			(unlocked yes)
			(layer "B.Fab")
			(hide yes)
			(effects
				(font
					(size 1 1)
					(thickness 0.15)
				)
				(justify mirror)
			)
		)
		(property "Author" "Antmicro"
			(at 0 0 90)
			(unlocked yes)
			(layer "B.Fab")
			(hide yes)
			(effects
				(font
					(size 1 1)
					(thickness 0.15)
				)
				(justify mirror)
			)
		)
		(property "License" "Apache-2.0"
			(at 0 0 90)
			(unlocked yes)
			(layer "B.Fab")
			(hide yes)
			(effects
				(font
					(size 1 1)
					(thickness 0.15)
				)
				(justify mirror)
			)
		)
		(sheetname "/Power/")
		(sheetfile "power.kicad_sch")
		(attr through_hole)
		(fp_poly
			(pts
				(xy -1.04 1.225) (xy 3.559 1.225) (xy 3.559 -5.326) (xy -1.04 -5.326)
			)
			(stroke
				(width 0.15)
				(type solid)
			)
			(fill no)
			(layer "B.SilkS")
		)
		(fp_poly
			(pts
				(xy -1.301 1.504001) (xy 3.819 1.504) (xy 3.819 -1.196) (xy -1.301 -1.196)
			)
			(stroke
				(width 0.05)
				(type solid)
			)
			(fill no)
			(layer "B.CrtYd")
		)
		(fp_poly
			(pts
				(xy -1.3 -4.196) (xy 3.819 -4.196) (xy 3.819 -5.596) (xy -1.3 -5.596)
			)
			(stroke
				(width 0.05)
				(type solid)
			)
			(fill no)
			(layer "B.CrtYd")
		)
		(fp_line
			(start 1.25 -1.8)
			(end 1.25 -2.499999)
			(stroke
				(width 0.15)
				(type solid)
			)
			(layer "B.Fab")
		)
		(fp_line
			(start 1.25 -2.499999)
			(end 1.95 -2.5)
			(stroke
				(width 0.15)
				(type solid)
			)
			(layer "B.Fab")
		)
		(fp_line
			(start 1.25 -2.499999)
			(end 1.25 -3.201)
			(stroke
				(width 0.15)
				(type solid)
			)
			(layer "B.Fab")
		)
		(fp_line
			(start 0.55 -2.5)
			(end 1.25 -2.499999)
			(stroke
				(width 0.15)
				(type solid)
			)
			(layer "B.Fab")
		)
		(fp_poly
			(pts
				(xy -0.791 -1.375999) (xy 3.309 -1.376) (xy 3.309 -3.625) (xy -0.791 -3.625001)
			)
			(stroke
				(width 0.15)
				(type solid)
			)
			(fill no)
			(layer "B.Fab")
		)
		(fp_text user "License: Apache-2.0"
			(at -7.21 -24.37 90)
			(layer "B.Fab")
			(effects
				(font
					(size 0.7 0.7)
					(thickness 0.15)
				)
				(justify left bottom mirror)
			)
		)
		(fp_text user "Author: Antmicro"
			(at -7.209999 -25.57 90)
			(layer "B.Fab")
			(effects
				(font
					(size 0.7 0.7)
					(thickness 0.15)
				)
				(justify left bottom mirror)
			)
		)
		(fp_text user "${REFERENCE}"
			(at -7.21 -23.17 90)
			(unlocked yes)
			(layer "B.Fab")
			(effects
				(font
					(size 0.7 0.7)
					(thickness 0.15)
				)
				(justify left bottom mirror)
			)
		)
		(pad "" np_thru_hole circle
			(at 0 0 270)
			(size 1.2 1.2)
			(drill 1.3)
			(layers "*.Cu" "*.Mask")
		)
		(pad "" np_thru_hole circle
			(at 2.5 0 270)
			(size 1.2 1.2)
			(drill 1.3)
			(layers "*.Cu" "*.Mask")
		)
	)
	(footprint "antmicro-footprints:C_0402_1005Metric"
		(layer "B.Cu")
		(at 235.57 77.51)
		(descr "Capacitor SMD 0402")
		(tags "capacitor SMD 0402")
		(property "Reference" "C152"
			(at -3.7 -0.32 0)
			(layer "B.SilkS")
			(effects
				(font
					(size 0.7 0.7)
					(thickness 0.15)
				)
				(justify right top mirror)
			)
		)
		(property "Value" "C_100n_0402"
			(at -1.022927 -2.155213 0)
			(layer "B.Fab")
			(effects
				(font
					(size 0.7 0.7)
					(thickness 0.15)
				)
				(justify right top mirror)
			)
		)
		(property "Datasheet" "https://www.murata.com/products/productdetail?partno=GRM155R61H104KE14%23"
			(at 0 0 0)
			(layer "B.Fab")
			(hide yes)
			(effects
				(font
					(size 1.27 1.27)
					(thickness 0.15)
				)
				(justify mirror)
			)
		)
		(property "Description" "SMD Multilayer Ceramic Capacitor, 0.1 µF, 50 V, 0402 [1005 Metric], ± 10%, X5R, GRM Series"
			(at 0 0 0)
			(layer "B.Fab")
			(hide yes)
			(effects
				(font
					(size 1.27 1.27)
					(thickness 0.15)
				)
				(justify mirror)
			)
		)
		(property "MPN" "GRM155R61H104KE14D"
			(at 0 0 180)
			(unlocked yes)
			(layer "B.Fab")
			(hide yes)
			(effects
				(font
					(size 1 1)
					(thickness 0.15)
				)
				(justify mirror)
			)
		)
		(property "Manufacturer" "Murata"
			(at 0 0 180)
			(unlocked yes)
			(layer "B.Fab")
			(hide yes)
			(effects
				(font
					(size 1 1)
					(thickness 0.15)
				)
				(justify mirror)
			)
		)
		(property "Val" "100n"
			(at 0 0 180)
			(unlocked yes)
			(layer "B.Fab")
			(hide yes)
			(effects
				(font
					(size 1 1)
					(thickness 0.15)
				)
				(justify mirror)
			)
		)
		(property "License" "Apache-2.0"
			(at 0 0 180)
			(unlocked yes)
			(layer "B.Fab")
			(hide yes)
			(effects
				(font
					(size 1 1)
					(thickness 0.15)
				)
				(justify mirror)
			)
		)
		(property "Author" "Antmicro"
			(at 0 0 180)
			(unlocked yes)
			(layer "B.Fab")
			(hide yes)
			(effects
				(font
					(size 1 1)
					(thickness 0.15)
				)
				(justify mirror)
			)
		)
		(property "Voltage" "50V"
			(at 0 0 180)
			(unlocked yes)
			(layer "B.Fab")
			(hide yes)
			(effects
				(font
					(size 1 1)
					(thickness 0.15)
				)
				(justify mirror)
			)
		)
		(property "Dielectric" "X5R"
			(at 0 0 180)
			(unlocked yes)
			(layer "B.Fab")
			(hide yes)
			(effects
				(font
					(size 1 1)
					(thickness 0.15)
				)
				(justify mirror)
			)
		)
		(sheetname "/USB Debug, PD/")
		(sheetfile "usb_debug_pd.kicad_sch")
		(attr smd)
		(fp_rect
			(start -0.925 0.47)
			(end 0.925 -0.47)
			(stroke
				(width 0.05)
				(type default)
			)
			(fill no)
			(layer "B.CrtYd")
		)
		(fp_line
			(start -0.494 -0.248)
			(end -0.494 0.25)
			(stroke
				(width 0.15)
				(type solid)
			)
			(layer "B.Fab")
		)
		(fp_line
			(start -0.494 0.25)
			(end 0.504 0.25)
			(stroke
				(width 0.15)
				(type solid)
			)
			(layer "B.Fab")
		)
		(fp_line
			(start 0.504 -0.248)
			(end -0.494 -0.248)
			(stroke
				(width 0.15)
				(type solid)
			)
			(layer "B.Fab")
		)
		(fp_line
			(start 0.504 0.25)
			(end 0.504 -0.248)
			(stroke
				(width 0.15)
				(type solid)
			)
			(layer "B.Fab")
		)
		(fp_text user "Author: Antmicro"
			(at -0.939 -3.399 0)
			(layer "B.Fab")
			(effects
				(font
					(size 0.7 0.7)
					(thickness 0.15)
				)
				(justify right top mirror)
			)
		)
		(fp_text user "${REFERENCE}"
			(at -0.939 -4.599 0)
			(layer "B.Fab")
			(effects
				(font
					(size 0.7 0.7)
					(thickness 0.15)
				)
				(justify right top mirror)
			)
		)
		(fp_text user "License: Apache-2.0"
			(at -0.939 -5.799 0)
			(layer "B.Fab")
			(effects
				(font
					(size 0.7 0.7)
					(thickness 0.15)
				)
				(justify right top mirror)
			)
		)
		(pad "1" smd roundrect
			(at -0.48 0)
			(size 0.59 0.64)
			(layers "B.Cu" "B.Mask" "B.Paste")
			(roundrect_rratio 0.25)
			(net 176 "/USB Debug, PD/USBC0_VBUS")
			(pintype "passive")
		)
		(pad "2" smd roundrect
			(at 0.48 0)
			(size 0.59 0.64)
			(layers "B.Cu" "B.Mask" "B.Paste")
			(roundrect_rratio 0.25)
			(net 1 "GND")
			(pintype "passive")
		)
	)
)
